(kicad_pcb
	(version 20260206)
	(generator "pcbnew")
	(generator_version "10.0")
	(general
		(thickness 1.6)
		(legacy_teardrops no)
	)
	(paper "A4")
	(title_block
		(title "03242023_DA0F0TMBIJ0_F0T_Motherboard_J_brd_V01_OCP.brd")
		(comment 1 "Grand Teton / footprints 5283-5288 of 6105")
	)
	(layers
		(0 "F.Cu" signal "TOP")
		(4 "In1.Cu" signal "GND")
		(6 "In2.Cu" signal "IN1")
		(8 "In3.Cu" signal "GND1")
		(10 "In4.Cu" signal "IN2")
		(12 "In5.Cu" signal "GND2")
		(14 "In6.Cu" signal "IN3")
		(16 "In7.Cu" signal "GND3")
		(18 "In8.Cu" signal "VCC")
		(20 "In9.Cu" signal "VCC1")
		(22 "In10.Cu" signal "GND4")
		(24 "In11.Cu" signal "IN4")
		(26 "In12.Cu" signal "GND5")
		(28 "In13.Cu" signal "IN5")
		(30 "In14.Cu" signal "GND6")
		(32 "In15.Cu" signal "IN6")
		(34 "In16.Cu" signal "GND7")
		(2 "B.Cu" signal "BOTTOM")
		(9 "F.Adhes" user "F.Adhesive")
		(11 "B.Adhes" user "B.Adhesive")
		(13 "F.Paste" user "Package Geometry/Pastemask Top")
		(15 "B.Paste" user "Package Geometry/Pastemask Bottom")
		(5 "F.SilkS" user "Ref Des/Silkscreen Top")
		(7 "B.SilkS" user "Ref Des/Silkscreen Bottom")
		(1 "F.Mask" user "Board Geometry/Soldermask Top")
		(3 "B.Mask" user "Board Geometry/Soldermask Bottom")
		(17 "Dwgs.User" user "User.Drawings")
		(19 "Cmts.User" user "User.Comments")
		(21 "Eco1.User" user "User.Eco1")
		(23 "Eco2.User" user "User.Eco2")
		(25 "Edge.Cuts" user "Board Geometry/Outline")
		(27 "Margin" user)
		(31 "F.CrtYd" user "Package Geometry/Place Bound Top")
		(29 "B.CrtYd" user "Package Geometry/Place Bound Bottom")
		(35 "F.Fab" user "Ref Des/Assembly Top")
		(33 "B.Fab" user "Ref Des/Assembly Bottom")
	)
	(footprint ""
		(layer "B.Cu")
		(at 118.158006 -212.049868)
		(property "Reference" "C481"
			(at 0 0 0)
			(layer "B.SilkS")
			(hide yes)
			(effects
				(font
					(size 1.27 1.27)
				)
				(justify mirror)
			)
		)
		(property "Value" ""
			(at 0 0 0)
			(layer "B.Fab")
			(effects
				(font
					(size 1.27 1.27)
				)
				(justify mirror)
			)
		)
		(duplicate_pad_numbers_are_jumpers no)
		(fp_line
			(start -1.524 -0.762)
			(end -1.524 0.762)
			(stroke
				(width 0.1524)
				(type default)
			)
			(layer "B.SilkS")
		)
		(fp_line
			(start -1.524 0.762)
			(end 1.524 0.762)
			(stroke
				(width 0.1524)
				(type default)
			)
			(layer "B.SilkS")
		)
		(fp_line
			(start 1.524 -0.762)
			(end -1.524 -0.762)
			(stroke
				(width 0.1524)
				(type default)
			)
			(layer "B.SilkS")
		)
		(fp_line
			(start 1.524 0.762)
			(end 1.524 -0.762)
			(stroke
				(width 0.1524)
				(type default)
			)
			(layer "B.SilkS")
		)
		(fp_line
			(start -1.1049 -0.724916)
			(end 1.1049 -0.724916)
			(stroke
				(width 0.1)
				(type default)
			)
			(layer "B.Fab")
		)
		(fp_line
			(start -1.1049 0.724916)
			(end -1.1049 -0.724916)
			(stroke
				(width 0.1)
				(type default)
			)
			(layer "B.Fab")
		)
		(fp_line
			(start 1.1049 -0.724916)
			(end 1.1049 0.724916)
			(stroke
				(width 0.1)
				(type default)
			)
			(layer "B.Fab")
		)
		(fp_line
			(start 1.1049 0.724916)
			(end -1.1049 0.724916)
			(stroke
				(width 0.1)
				(type default)
			)
			(layer "B.Fab")
		)
		(pad "1" smd rect
			(at 0.889 0)
			(size 1.016 1.27)
			(layers "B.Cu" "B.Mask" "B.Paste")
			(net "PVCCINFAON_CPU1")
		)
		(pad "2" smd rect
			(at -0.889 0)
			(size 1.016 1.27)
			(layers "B.Cu" "B.Mask" "B.Paste")
			(net "GND")
		)
	)
	(footprint ""
		(layer "B.Cu")
		(at 404.09241 -193.05143 -90)
		(property "Reference" "R1233"
			(at 0 0 90)
			(layer "B.SilkS")
			(hide yes)
			(effects
				(font
					(size 1.27 1.27)
				)
				(justify mirror)
			)
		)
		(property "Value" ""
			(at 0 0 90)
			(layer "B.Fab")
			(effects
				(font
					(size 1.27 1.27)
				)
				(justify mirror)
			)
		)
		(duplicate_pad_numbers_are_jumpers no)
		(fp_line
			(start -0.7874 0.4064)
			(end 0.7874 0.4064)
			(stroke
				(width 0.1524)
				(type default)
			)
			(layer "B.SilkS")
		)
		(fp_line
			(start 0.7874 0.4064)
			(end 0.7874 -0.4064)
			(stroke
				(width 0.1524)
				(type default)
			)
			(layer "B.SilkS")
		)
		(fp_line
			(start -0.7874 -0.4064)
			(end -0.7874 0.4064)
			(stroke
				(width 0.1524)
				(type default)
			)
			(layer "B.SilkS")
		)
		(fp_line
			(start 0.7874 -0.4064)
			(end -0.7874 -0.4064)
			(stroke
				(width 0.1524)
				(type default)
			)
			(layer "B.SilkS")
		)
		(fp_line
			(start -0.67945 0.3048)
			(end -0.120396 0.3048)
			(stroke
				(width 0.1)
				(type default)
			)
			(layer "B.Fab")
		)
		(fp_line
			(start -0.120396 0.3048)
			(end -0.120396 0.2794)
			(stroke
				(width 0.1)
				(type default)
			)
			(layer "B.Fab")
		)
		(fp_line
			(start 0.12065 0.3048)
			(end 0.67945 0.3048)
			(stroke
				(width 0.1)
				(type default)
			)
			(layer "B.Fab")
		)
		(fp_line
			(start 0.67945 0.3048)
			(end 0.67945 -0.305054)
			(stroke
				(width 0.1)
				(type default)
			)
			(layer "B.Fab")
		)
		(fp_line
			(start -0.120396 0.2794)
			(end 0.12065 0.2794)
			(stroke
				(width 0.1)
				(type default)
			)
			(layer "B.Fab")
		)
		(fp_line
			(start 0.12065 0.2794)
			(end 0.12065 0.3048)
			(stroke
				(width 0.1)
				(type default)
			)
			(layer "B.Fab")
		)
		(fp_line
			(start -0.12065 -0.2794)
			(end -0.12065 -0.3048)
			(stroke
				(width 0.1)
				(type default)
			)
			(layer "B.Fab")
		)
		(fp_line
			(start 0.12065 -0.2794)
			(end -0.12065 -0.2794)
			(stroke
				(width 0.1)
				(type default)
			)
			(layer "B.Fab")
		)
		(fp_line
			(start -0.67945 -0.3048)
			(end -0.67945 0.3048)
			(stroke
				(width 0.1)
				(type default)
			)
			(layer "B.Fab")
		)
		(fp_line
			(start -0.12065 -0.3048)
			(end -0.67945 -0.3048)
			(stroke
				(width 0.1)
				(type default)
			)
			(layer "B.Fab")
		)
		(fp_line
			(start 0.12065 -0.305054)
			(end 0.12065 -0.2794)
			(stroke
				(width 0.1)
				(type default)
			)
			(layer "B.Fab")
		)
		(fp_line
			(start 0.67945 -0.305054)
			(end 0.12065 -0.305054)
			(stroke
				(width 0.1)
				(type default)
			)
			(layer "B.Fab")
		)
		(pad "1" smd circle
			(at 0.40005 0 90)
			(size 0 0)
			(layers "B.Cu" "B.Mask" "B.Paste")
			(net "PVNN_TERM_CPU0")
		)
		(pad "2" smd circle
			(at -0.40005 0 90)
			(size 0 0)
			(layers "B.Cu" "B.Mask" "B.Paste")
			(net "PUD_XTAL_CPU0_MODE1")
		)
	)
	(footprint ""
		(layer "B.Cu")
		(at 76.463652 -181.65699 -90)
		(property "Reference" "R758"
			(at 0 0 90)
			(layer "B.SilkS")
			(hide yes)
			(effects
				(font
					(size 1.27 1.27)
				)
				(justify mirror)
			)
		)
		(property "Value" ""
			(at 0 0 90)
			(layer "B.Fab")
			(effects
				(font
					(size 1.27 1.27)
				)
				(justify mirror)
			)
		)
		(duplicate_pad_numbers_are_jumpers no)
		(fp_line
			(start -0.7874 0.4064)
			(end 0.7874 0.4064)
			(stroke
				(width 0.1524)
				(type default)
			)
			(layer "B.SilkS")
		)
		(fp_line
			(start 0.7874 0.4064)
			(end 0.7874 -0.4064)
			(stroke
				(width 0.1524)
				(type default)
			)
			(layer "B.SilkS")
		)
		(fp_line
			(start -0.7874 -0.4064)
			(end -0.7874 0.4064)
			(stroke
				(width 0.1524)
				(type default)
			)
			(layer "B.SilkS")
		)
		(fp_line
			(start 0.7874 -0.4064)
			(end -0.7874 -0.4064)
			(stroke
				(width 0.1524)
				(type default)
			)
			(layer "B.SilkS")
		)
		(fp_line
			(start -0.67945 0.3048)
			(end -0.120396 0.3048)
			(stroke
				(width 0.1)
				(type default)
			)
			(layer "B.Fab")
		)
		(fp_line
			(start -0.120396 0.3048)
			(end -0.120396 0.2794)
			(stroke
				(width 0.1)
				(type default)
			)
			(layer "B.Fab")
		)
		(fp_line
			(start 0.12065 0.3048)
			(end 0.67945 0.3048)
			(stroke
				(width 0.1)
				(type default)
			)
			(layer "B.Fab")
		)
		(fp_line
			(start 0.67945 0.3048)
			(end 0.67945 -0.305054)
			(stroke
				(width 0.1)
				(type default)
			)
			(layer "B.Fab")
		)
		(fp_line
			(start -0.120396 0.2794)
			(end 0.12065 0.2794)
			(stroke
				(width 0.1)
				(type default)
			)
			(layer "B.Fab")
		)
		(fp_line
			(start 0.12065 0.2794)
			(end 0.12065 0.3048)
			(stroke
				(width 0.1)
				(type default)
			)
			(layer "B.Fab")
		)
		(fp_line
			(start -0.12065 -0.2794)
			(end -0.12065 -0.3048)
			(stroke
				(width 0.1)
				(type default)
			)
			(layer "B.Fab")
		)
		(fp_line
			(start 0.12065 -0.2794)
			(end -0.12065 -0.2794)
			(stroke
				(width 0.1)
				(type default)
			)
			(layer "B.Fab")
		)
		(fp_line
			(start -0.67945 -0.3048)
			(end -0.67945 0.3048)
			(stroke
				(width 0.1)
				(type default)
			)
			(layer "B.Fab")
		)
		(fp_line
			(start -0.12065 -0.3048)
			(end -0.67945 -0.3048)
			(stroke
				(width 0.1)
				(type default)
			)
			(layer "B.Fab")
		)
		(fp_line
			(start 0.12065 -0.305054)
			(end 0.12065 -0.2794)
			(stroke
				(width 0.1)
				(type default)
			)
			(layer "B.Fab")
		)
		(fp_line
			(start 0.67945 -0.305054)
			(end 0.12065 -0.305054)
			(stroke
				(width 0.1)
				(type default)
			)
			(layer "B.Fab")
		)
		(pad "1" smd circle
			(at 0.40005 0 90)
			(size 0 0)
			(layers "B.Cu" "B.Mask" "B.Paste")
			(net "PVNN_TERM_CPU0")
		)
		(pad "2" smd circle
			(at -0.40005 0 90)
			(size 0 0)
			(layers "B.Cu" "B.Mask" "B.Paste")
			(net "H_CPU_PREQ_QS_GTL_N")
		)
	)
	(footprint ""
		(layer "B.Cu")
		(at 233.9086 -250.505468 180)
		(property "Reference" "C2259"
			(at 0 0 0)
			(layer "B.SilkS")
			(hide yes)
			(effects
				(font
					(size 1.27 1.27)
				)
				(justify mirror)
			)
		)
		(property "Value" ""
			(at 0 0 0)
			(layer "B.Fab")
			(effects
				(font
					(size 1.27 1.27)
				)
				(justify mirror)
			)
		)
		(duplicate_pad_numbers_are_jumpers no)
		(fp_line
			(start 0.7874 0.4064)
			(end 0.7874 -0.4064)
			(stroke
				(width 0.1524)
				(type default)
			)
			(layer "B.SilkS")
		)
		(fp_line
			(start 0.7874 -0.4064)
			(end -0.7874 -0.4064)
			(stroke
				(width 0.1524)
				(type default)
			)
			(layer "B.SilkS")
		)
		(fp_line
			(start -0.7874 0.4064)
			(end 0.7874 0.4064)
			(stroke
				(width 0.1524)
				(type default)
			)
			(layer "B.SilkS")
		)
		(fp_line
			(start -0.7874 -0.4064)
			(end -0.7874 0.4064)
			(stroke
				(width 0.1524)
				(type default)
			)
			(layer "B.SilkS")
		)
		(fp_line
			(start 0.67945 0.3048)
			(end 0.67945 -0.305054)
			(stroke
				(width 0.1)
				(type default)
			)
			(layer "B.Fab")
		)
		(fp_line
			(start 0.67945 -0.305054)
			(end 0.12065 -0.305054)
			(stroke
				(width 0.1)
				(type default)
			)
			(layer "B.Fab")
		)
		(fp_line
			(start 0.12065 0.3048)
			(end 0.67945 0.3048)
			(stroke
				(width 0.1)
				(type default)
			)
			(layer "B.Fab")
		)
		(fp_line
			(start 0.12065 0.2794)
			(end 0.12065 0.3048)
			(stroke
				(width 0.1)
				(type default)
			)
			(layer "B.Fab")
		)
		(fp_line
			(start 0.12065 -0.2794)
			(end -0.12065 -0.2794)
			(stroke
				(width 0.1)
				(type default)
			)
			(layer "B.Fab")
		)
		(fp_line
			(start 0.12065 -0.305054)
			(end 0.12065 -0.2794)
			(stroke
				(width 0.1)
				(type default)
			)
			(layer "B.Fab")
		)
		(fp_line
			(start -0.120396 0.3048)
			(end -0.120396 0.2794)
			(stroke
				(width 0.1)
				(type default)
			)
			(layer "B.Fab")
		)
		(fp_line
			(start -0.120396 0.2794)
			(end 0.12065 0.2794)
			(stroke
				(width 0.1)
				(type default)
			)
			(layer "B.Fab")
		)
		(fp_line
			(start -0.12065 -0.2794)
			(end -0.12065 -0.3048)
			(stroke
				(width 0.1)
				(type default)
			)
			(layer "B.Fab")
		)
		(fp_line
			(start -0.12065 -0.3048)
			(end -0.67945 -0.3048)
			(stroke
				(width 0.1)
				(type default)
			)
			(layer "B.Fab")
		)
		(fp_line
			(start -0.67945 0.3048)
			(end -0.120396 0.3048)
			(stroke
				(width 0.1)
				(type default)
			)
			(layer "B.Fab")
		)
		(fp_line
			(start -0.67945 -0.3048)
			(end -0.67945 0.3048)
			(stroke
				(width 0.1)
				(type default)
			)
			(layer "B.Fab")
		)
		(pad "1" smd circle
			(at 0.40005 0)
			(size 0 0)
			(layers "B.Cu" "B.Mask" "B.Paste")
			(net "VFG_3P3A_CLK_GEN")
		)
		(pad "2" smd circle
			(at -0.40005 0)
			(size 0 0)
			(layers "B.Cu" "B.Mask" "B.Paste")
			(net "GND")
		)
	)
	(footprint ""
		(layer "B.Cu")
		(at 401.828 -192.623948 -90)
		(property "Reference" "R4297"
			(at 0 0 90)
			(layer "B.SilkS")
			(hide yes)
			(effects
				(font
					(size 1.27 1.27)
				)
				(justify mirror)
			)
		)
		(property "Value" ""
			(at 0 0 90)
			(layer "B.Fab")
			(effects
				(font
					(size 1.27 1.27)
				)
				(justify mirror)
			)
		)
		(duplicate_pad_numbers_are_jumpers no)
		(fp_line
			(start -0.7874 0.4064)
			(end 0.7874 0.4064)
			(stroke
				(width 0.1524)
				(type default)
			)
			(layer "B.SilkS")
		)
		(fp_line
			(start 0.7874 0.4064)
			(end 0.7874 -0.4064)
			(stroke
				(width 0.1524)
				(type default)
			)
			(layer "B.SilkS")
		)
		(fp_line
			(start -0.7874 -0.4064)
			(end -0.7874 0.4064)
			(stroke
				(width 0.1524)
				(type default)
			)
			(layer "B.SilkS")
		)
		(fp_line
			(start 0.7874 -0.4064)
			(end -0.7874 -0.4064)
			(stroke
				(width 0.1524)
				(type default)
			)
			(layer "B.SilkS")
		)
		(fp_line
			(start -0.67945 0.3048)
			(end -0.120396 0.3048)
			(stroke
				(width 0.1)
				(type default)
			)
			(layer "B.Fab")
		)
		(fp_line
			(start -0.120396 0.3048)
			(end -0.120396 0.2794)
			(stroke
				(width 0.1)
				(type default)
			)
			(layer "B.Fab")
		)
		(fp_line
			(start 0.12065 0.3048)
			(end 0.67945 0.3048)
			(stroke
				(width 0.1)
				(type default)
			)
			(layer "B.Fab")
		)
		(fp_line
			(start 0.67945 0.3048)
			(end 0.67945 -0.305054)
			(stroke
				(width 0.1)
				(type default)
			)
			(layer "B.Fab")
		)
		(fp_line
			(start -0.120396 0.2794)
			(end 0.12065 0.2794)
			(stroke
				(width 0.1)
				(type default)
			)
			(layer "B.Fab")
		)
		(fp_line
			(start 0.12065 0.2794)
			(end 0.12065 0.3048)
			(stroke
				(width 0.1)
				(type default)
			)
			(layer "B.Fab")
		)
		(fp_line
			(start -0.12065 -0.2794)
			(end -0.12065 -0.3048)
			(stroke
				(width 0.1)
				(type default)
			)
			(layer "B.Fab")
		)
		(fp_line
			(start 0.12065 -0.2794)
			(end -0.12065 -0.2794)
			(stroke
				(width 0.1)
				(type default)
			)
			(layer "B.Fab")
		)
		(fp_line
			(start -0.67945 -0.3048)
			(end -0.67945 0.3048)
			(stroke
				(width 0.1)
				(type default)
			)
			(layer "B.Fab")
		)
		(fp_line
			(start -0.12065 -0.3048)
			(end -0.67945 -0.3048)
			(stroke
				(width 0.1)
				(type default)
			)
			(layer "B.Fab")
		)
		(fp_line
			(start 0.12065 -0.305054)
			(end 0.12065 -0.2794)
			(stroke
				(width 0.1)
				(type default)
			)
			(layer "B.Fab")
		)
		(fp_line
			(start 0.67945 -0.305054)
			(end 0.12065 -0.305054)
			(stroke
				(width 0.1)
				(type default)
			)
			(layer "B.Fab")
		)
		(pad "1" smd circle
			(at 0.40005 0 90)
			(size 0 0)
			(layers "B.Cu" "B.Mask" "B.Paste")
			(net "PWRGD_DRAMPWRGD_CPU0_EF_LVC1_R2")
		)
		(pad "2" smd circle
			(at -0.40005 0 90)
			(size 0 0)
			(layers "B.Cu" "B.Mask" "B.Paste")
			(net "PWRGD_DRAMPWRGD_CPU0_EF_LVC1_R")
		)
	)
	(footprint ""
		(layer "B.Cu")
		(at 286.478726 -193.691256 -90)
		(property "Reference" "R840"
			(at 0 0 90)
			(layer "B.SilkS")
			(hide yes)
			(effects
				(font
					(size 1.27 1.27)
				)
				(justify mirror)
			)
		)
		(property "Value" ""
			(at 0 0 90)
			(layer "B.Fab")
			(effects
				(font
					(size 1.27 1.27)
				)
				(justify mirror)
			)
		)
		(duplicate_pad_numbers_are_jumpers no)
		(fp_line
			(start -0.7874 0.4064)
			(end 0.7874 0.4064)
			(stroke
				(width 0.1524)
				(type default)
			)
			(layer "B.SilkS")
		)
		(fp_line
			(start 0.7874 0.4064)
			(end 0.7874 -0.4064)
			(stroke
				(width 0.1524)
				(type default)
			)
			(layer "B.SilkS")
		)
		(fp_line
			(start -0.7874 -0.4064)
			(end -0.7874 0.4064)
			(stroke
				(width 0.1524)
				(type default)
			)
			(layer "B.SilkS")
		)
		(fp_line
			(start 0.7874 -0.4064)
			(end -0.7874 -0.4064)
			(stroke
				(width 0.1524)
				(type default)
			)
			(layer "B.SilkS")
		)
		(fp_line
			(start -0.67945 0.3048)
			(end -0.120396 0.3048)
			(stroke
				(width 0.1)
				(type default)
			)
			(layer "B.Fab")
		)
		(fp_line
			(start -0.120396 0.3048)
			(end -0.120396 0.2794)
			(stroke
				(width 0.1)
				(type default)
			)
			(layer "B.Fab")
		)
		(fp_line
			(start 0.12065 0.3048)
			(end 0.67945 0.3048)
			(stroke
				(width 0.1)
				(type default)
			)
			(layer "B.Fab")
		)
		(fp_line
			(start 0.67945 0.3048)
			(end 0.67945 -0.305054)
			(stroke
				(width 0.1)
				(type default)
			)
			(layer "B.Fab")
		)
		(fp_line
			(start -0.120396 0.2794)
			(end 0.12065 0.2794)
			(stroke
				(width 0.1)
				(type default)
			)
			(layer "B.Fab")
		)
		(fp_line
			(start 0.12065 0.2794)
			(end 0.12065 0.3048)
			(stroke
				(width 0.1)
				(type default)
			)
			(layer "B.Fab")
		)
		(fp_line
			(start -0.12065 -0.2794)
			(end -0.12065 -0.3048)
			(stroke
				(width 0.1)
				(type default)
			)
			(layer "B.Fab")
		)
		(fp_line
			(start 0.12065 -0.2794)
			(end -0.12065 -0.2794)
			(stroke
				(width 0.1)
				(type default)
			)
			(layer "B.Fab")
		)
		(fp_line
			(start -0.67945 -0.3048)
			(end -0.67945 0.3048)
			(stroke
				(width 0.1)
				(type default)
			)
			(layer "B.Fab")
		)
		(fp_line
			(start -0.12065 -0.3048)
			(end -0.67945 -0.3048)
			(stroke
				(width 0.1)
				(type default)
			)
			(layer "B.Fab")
		)
		(fp_line
			(start 0.12065 -0.305054)
			(end 0.12065 -0.2794)
			(stroke
				(width 0.1)
				(type default)
			)
			(layer "B.Fab")
		)
		(fp_line
			(start 0.67945 -0.305054)
			(end 0.12065 -0.305054)
			(stroke
				(width 0.1)
				(type default)
			)
			(layer "B.Fab")
		)
		(pad "1" smd circle
			(at 0.40005 0 90)
			(size 0 0)
			(layers "B.Cu" "B.Mask" "B.Paste")
			(net "PVCCD_HV_CPU0")
		)
		(pad "2" smd circle
			(at -0.40005 0 90)
			(size 0 0)
			(layers "B.Cu" "B.Mask" "B.Paste")
			(net "RST_M_AB_CPU0_FPGA_N")
		)
	)
)
